FILE_TYPE = CONNECTIVITY;
{Allegro Design Entry HDL 17.4-2019 S026 (4007227) 1/17/2022}
"PAGE_NUMBER" = 74;
0"NC";
1"PVDD_33_S5\g";
2"GND\g";
3"GND\g";
4"PVDD18_S5_P1\g";
5"PVDD18_S5_P1\g";
6"GND\g";
%"Q_CAP"
"1","(-8550,3000)","0","pure_quanta","I1";
;
LOCATION"C2661"
$SEC"1"
CDS_SEC"1"
PACK_TYPE"C0402"
VOLTAGE"4V"
VALUE"22UF"
TOLERANCE"20%"
MATERIAL"X6S"
CDS_LIB"pure_quanta"
PART_NUMBER"CH622KMEB02";
"B"
$PN"2"3;
"A"
$PN"1"5;
%"Q_CAP"
"1","(-7650,3775)","0","pure_quanta","I10";
;
LOCATION"C2665"
$SEC"1"
CDS_SEC"1"
PACK_TYPE"C0402"
VOLTAGE"4V"
VALUE"22UF"
TOLERANCE"20%"
MATERIAL"X6S"
CDS_LIB"pure_quanta"
PART_NUMBER"CH622KMEB02";
"B"
$PN"2"6;
"A"
$PN"1"4;
%"Q_CAP"
"1","(-7200,3775)","0","pure_quanta","I11";
;
LOCATION"C2667"
$SEC"1"
CDS_SEC"1"
PACK_TYPE"C0402"
VOLTAGE"4V"
VALUE"22UF"
TOLERANCE"20%"
MATERIAL"X6S"
CDS_LIB"pure_quanta"
PART_NUMBER"CH622KMEB02";
"B"
$PN"2"6;
"A"
$PN"1"4;
%"Q_CAP"
"1","(-6750,3775)","0","pure_quanta","I12";
;
LOCATION"C2668"
$SEC"1"
CDS_SEC"1"
PACK_TYPE"C0402"
VOLTAGE"4V"
VALUE"22UF"
TOLERANCE"20%"
MATERIAL"X6S"
CDS_LIB"pure_quanta"
PART_NUMBER"CH622KMEB02";
"B"
$PN"2"6;
"A"
$PN"1"4;
%"Q_CAP"
"1","(-6300,3775)","0","pure_quanta","I13";
;
LOCATION"C2669"
$SEC"1"
CDS_SEC"1"
PACK_TYPE"C0402"
VOLTAGE"4V"
VALUE"22UF"
TOLERANCE"20%"
MATERIAL"X6S"
CDS_LIB"pure_quanta"
PART_NUMBER"CH622KMEB02";
"B"
$PN"2"6;
"A"
$PN"1"4;
%"Q_CAP"
"1","(-5850,3775)","0","pure_quanta","I14";
;
LOCATION"C2670"
$SEC"1"
CDS_SEC"1"
PACK_TYPE"C0402"
VOLTAGE"4V"
VALUE"22UF"
TOLERANCE"20%"
MATERIAL"X6S"
CDS_LIB"pure_quanta"
PART_NUMBER"CH622KMEB02";
"B"
$PN"2"6;
"A"
$PN"1"4;
%"Q_CAP"
"1","(-5400,3775)","0","pure_quanta","I15";
;
LOCATION"C2671"
$SEC"1"
CDS_SEC"1"
PACK_TYPE"C0402"
VOLTAGE"4V"
VALUE"22UF"
TOLERANCE"20%"
MATERIAL"X6S"
CDS_LIB"pure_quanta"
PART_NUMBER"CH622KMEB02";
"B"
$PN"2"6;
"A"
$PN"1"4;
%"Q_CAP"
"1","(-4950,3775)","0","pure_quanta","I16";
;
LOCATION"C2672"
$SEC"1"
CDS_SEC"1"
PACK_TYPE"C0402"
VOLTAGE"4V"
VALUE"22UF"
TOLERANCE"20%"
MATERIAL"X6S"
CDS_LIB"pure_quanta"
PART_NUMBER"CH622KMEB02";
"B"
$PN"2"6;
"A"
$PN"1"4;
%"UNIVERSAL_GND"
"1","(-4550,3400)","0","pure_quanta_power","I17";
;
CDS_LIB"pure_quanta_power"
HDL_POWER"GND";
"A"6;
%"Q_CAP"
"1","(-4550,3775)","0","pure_quanta","I18";
;
LOCATION"C2673"
$SEC"1"
CDS_SEC"1"
PACK_TYPE"C0402"
VOLTAGE"4V"
VALUE"22UF"
TOLERANCE"20%"
MATERIAL"X6S"
CDS_LIB"pure_quanta"
PART_NUMBER"CH622KMEB02";
"B"
$PN"2"6;
"A"
$PN"1"4;
%"UNIVERSAL_POWER"
"1","(-8550,3275)","0","pure_quanta_power","I2";
;
HDL_POWER"PVDD18_S5_P1"
CDS_LIB"pure_quanta_power";
"A"5;
%"UNIVERSAL_POWER"
"1","(-8475,5675)","0","pure_quanta_power","I23";
;
HDL_POWER"PVDD_33_S5"
CDS_LIB"pure_quanta_power";
"A"1;
%"UNIVERSAL_GND"
"1","(-8025,5025)","0","pure_quanta_power","I24";
;
CDS_LIB"pure_quanta_power"
HDL_POWER"GND";
"A"2;
%"Q_CAP"
"1","(-8025,5400)","0","pure_quanta","I25";
;
LOCATION"C2662"
$SEC"1"
CDS_SEC"1"
PACK_TYPE"C0402"
TOLERANCE"20%"
VALUE"10UF"
VOLTAGE"6.3V"
MATERIAL"X6S"
CDS_LIB"pure_quanta"
PART_NUMBER"CH6101MEB01";
"B"
$PN"2"2;
"A"
$PN"1"1;
%"Q_CAP"
"1","(-8475,5400)","0","pure_quanta","I26";
;
LOCATION"C2659"
$SEC"1"
CDS_SEC"1"
PACK_TYPE"C0402"
TOLERANCE"20%"
VALUE"10UF"
VOLTAGE"6.3V"
MATERIAL"X6S"
CDS_LIB"pure_quanta"
PART_NUMBER"CH6101MEB01";
"B"
$PN"2"2;
"A"
$PN"1"1;
%"Q_CAP"
"1","(-8550,3775)","0","pure_quanta","I3";
;
LOCATION"C2660"
$SEC"1"
CDS_SEC"1"
PACK_TYPE"C0402"
VOLTAGE"4V"
VALUE"22UF"
TOLERANCE"20%"
MATERIAL"X6S"
CDS_LIB"pure_quanta"
PART_NUMBER"CH622KMEB02";
"B"
$PN"2"6;
"A"
$PN"1"4;
%"UNIVERSAL_POWER"
"1","(-8550,4050)","0","pure_quanta_power","I4";
;
HDL_POWER"PVDD18_S5_P1"
CDS_LIB"pure_quanta_power";
"A"4;
%"UNIVERSAL_GND"
"1","(-8100,2625)","0","pure_quanta_power","I7";
;
CDS_LIB"pure_quanta_power"
HDL_POWER"GND";
"A"3;
%"Q_CAP"
"1","(-8100,3000)","0","pure_quanta","I8";
;
LOCATION"C2664"
$SEC"1"
CDS_SEC"1"
PACK_TYPE"C0402"
VOLTAGE"4V"
VALUE"22UF"
TOLERANCE"20%"
MATERIAL"X6S"
CDS_LIB"pure_quanta"
PART_NUMBER"CH622KMEB02";
"B"
$PN"2"3;
"A"
$PN"1"5;
%"Q_CAP"
"1","(-8100,3775)","0","pure_quanta","I9";
;
LOCATION"C2663"
$SEC"1"
CDS_SEC"1"
PACK_TYPE"C0402"
VOLTAGE"4V"
VALUE"22UF"
TOLERANCE"20%"
MATERIAL"X6S"
CDS_LIB"pure_quanta"
PART_NUMBER"CH622KMEB02";
"B"
$PN"2"6;
"A"
$PN"1"4;
END.
